# T6G (Grand Teton) — schematic netlist excerpt (pin names and nets, part order shuffled) for the footprints in the layout excerpt that follows; sources: Cadence DE-HDL packaged netlist, KiCad conversion of 04192023_DAF0TMB3IC0_F0TG_MB_C_brd_V02_OCP.brd

C662  Q_CAP  0.1UF 10V 10% X7S  pkg C0201  page 290 : A = P0V9_CPU0_RT1_2A ; B = GND
C2663  Q_CAP  22UF 4V 20% X6S  pkg C0402  page 75 : A = PVDD18_S5_P1 ; B = GND
R4129  Q_RES  100K 1% CHIP  pkg 0402LF  page 125 : A = P3V3_AUX ; B = PRSNT_CABLE_GPU_B3_ISO_N

(kicad_pcb
	(version 20260206)
	(generator "pcbnew")
	(generator_version "10.0")
	(general
		(thickness 1.6)
		(legacy_teardrops no)
	)
	(paper "A4")
	(title_block
		(title "04192023_DAF0TMB3IC0_F0TG_MB_C_brd_V02_OCP.brd")
		(comment 1 "Grand Teton / footprints 8011-8013 of 8354")
	)
	(layers
		(0 "F.Cu" signal "TOP")
		(4 "In1.Cu" signal "GND")
		(6 "In2.Cu" signal "IN1")
		(8 "In3.Cu" signal "GND1")
		(10 "In4.Cu" signal "IN2")
		(12 "In5.Cu" signal "GND2")
		(14 "In6.Cu" signal "IN3")
		(16 "In7.Cu" signal "GND3")
		(18 "In8.Cu" signal "VCC")
		(20 "In9.Cu" signal "VCC1")
		(22 "In10.Cu" signal "GND4")
		(24 "In11.Cu" signal "IN4")
		(26 "In12.Cu" signal "GND5")
		(28 "In13.Cu" signal "IN5")
		(30 "In14.Cu" signal "GND6")
		(32 "In15.Cu" signal "IN6")
		(34 "In16.Cu" signal "GND7")
		(2 "B.Cu" signal "BOTTOM")
		(9 "F.Adhes" user "F.Adhesive")
		(11 "B.Adhes" user "B.Adhesive")
		(13 "F.Paste" user "Package Geometry/Pastemask Top")
		(15 "B.Paste" user "Package Geometry/Pastemask Bottom")
		(5 "F.SilkS" user "Ref Des/Silkscreen Top")
		(7 "B.SilkS" user "Ref Des/Silkscreen Bottom")
		(1 "F.Mask" user "Board Geometry/Soldermask Top")
		(3 "B.Mask" user "Board Geometry/Soldermask Bottom")
		(17 "Dwgs.User" user "User.Drawings")
		(19 "Cmts.User" user "User.Comments")
		(21 "Eco1.User" user "User.Eco1")
		(23 "Eco2.User" user "User.Eco2")
		(25 "Edge.Cuts" user "Board Geometry/Outline")
		(27 "Margin" user)
		(31 "F.CrtYd" user "Package Geometry/Place Bound Top")
		(29 "B.CrtYd" user "Package Geometry/Place Bound Bottom")
		(35 "F.Fab" user "Ref Des/Assembly Top")
		(33 "B.Fab" user "Ref Des/Assembly Bottom")
	)
	(footprint ""
		(layer "B.Cu")
		(at 163.387532 -435.93258 90)
		(property "Reference" "R4129"
			(at 0 0 90)
			(layer "B.SilkS")
			(hide yes)
			(effects
				(font
					(size 1.27 1.27)
				)
				(justify mirror)
			)
		)
		(property "Value" ""
			(at 0 0 90)
			(layer "B.Fab")
			(effects
				(font
					(size 1.27 1.27)
				)
				(justify mirror)
			)
		)
		(duplicate_pad_numbers_are_jumpers no)
		(fp_line
			(start 0.7874 -0.4064)
			(end -0.7874 -0.4064)
			(stroke
				(width 0.1524)
				(type default)
			)
			(layer "B.SilkS")
		)
		(fp_line
			(start -0.7874 -0.4064)
			(end -0.7874 0.4064)
			(stroke
				(width 0.1524)
				(type default)
			)
			(layer "B.SilkS")
		)
		(fp_line
			(start 0.7874 0.4064)
			(end 0.7874 -0.4064)
			(stroke
				(width 0.1524)
				(type default)
			)
			(layer "B.SilkS")
		)
		(fp_line
			(start -0.7874 0.4064)
			(end 0.7874 0.4064)
			(stroke
				(width 0.1524)
				(type default)
			)
			(layer "B.SilkS")
		)
		(fp_line
			(start 0.67945 -0.305054)
			(end 0.12065 -0.305054)
			(stroke
				(width 0.1)
				(type default)
			)
			(layer "B.Fab")
		)
		(fp_line
			(start 0.12065 -0.305054)
			(end 0.12065 -0.2794)
			(stroke
				(width 0.1)
				(type default)
			)
			(layer "B.Fab")
		)
		(fp_line
			(start -0.12065 -0.3048)
			(end -0.67945 -0.3048)
			(stroke
				(width 0.1)
				(type default)
			)
			(layer "B.Fab")
		)
		(fp_line
			(start -0.67945 -0.3048)
			(end -0.67945 0.3048)
			(stroke
				(width 0.1)
				(type default)
			)
			(layer "B.Fab")
		)
		(fp_line
			(start 0.12065 -0.2794)
			(end -0.12065 -0.2794)
			(stroke
				(width 0.1)
				(type default)
			)
			(layer "B.Fab")
		)
		(fp_line
			(start -0.12065 -0.2794)
			(end -0.12065 -0.3048)
			(stroke
				(width 0.1)
				(type default)
			)
			(layer "B.Fab")
		)
		(fp_line
			(start 0.12065 0.2794)
			(end 0.12065 0.3048)
			(stroke
				(width 0.1)
				(type default)
			)
			(layer "B.Fab")
		)
		(fp_line
			(start -0.120396 0.2794)
			(end 0.12065 0.2794)
			(stroke
				(width 0.1)
				(type default)
			)
			(layer "B.Fab")
		)
		(fp_line
			(start 0.67945 0.3048)
			(end 0.67945 -0.305054)
			(stroke
				(width 0.1)
				(type default)
			)
			(layer "B.Fab")
		)
		(fp_line
			(start 0.12065 0.3048)
			(end 0.67945 0.3048)
			(stroke
				(width 0.1)
				(type default)
			)
			(layer "B.Fab")
		)
		(fp_line
			(start -0.120396 0.3048)
			(end -0.120396 0.2794)
			(stroke
				(width 0.1)
				(type default)
			)
			(layer "B.Fab")
		)
		(fp_line
			(start -0.67945 0.3048)
			(end -0.120396 0.3048)
			(stroke
				(width 0.1)
				(type default)
			)
			(layer "B.Fab")
		)
		(pad "1" smd circle
			(at 0.40005 0 270)
			(size 0 0)
			(layers "B.Cu" "B.Mask" "B.Paste")
			(net "P3V3_AUX")
		)
		(pad "2" smd circle
			(at -0.40005 0 270)
			(size 0 0)
			(layers "B.Cu" "B.Mask" "B.Paste")
			(net "PRSNT_CABLE_GPU_B3_ISO_N")
		)
	)
	(footprint ""
		(layer "B.Cu")
		(at 339.646006 -396.393162 -90)
		(property "Reference" "C662"
			(at 0 0 90)
			(layer "B.SilkS")
			(hide yes)
			(effects
				(font
					(size 1.27 1.27)
				)
				(justify mirror)
			)
		)
		(property "Value" ""
			(at 0 0 90)
			(layer "B.Fab")
			(effects
				(font
					(size 1.27 1.27)
				)
				(justify mirror)
			)
		)
		(duplicate_pad_numbers_are_jumpers no)
		(fp_line
			(start -0.299974 0.150114)
			(end 0.299974 0.150114)
			(stroke
				(width 0.1)
				(type default)
			)
			(layer "B.Fab")
		)
		(fp_line
			(start 0.299974 0.150114)
			(end 0.299974 -0.150114)
			(stroke
				(width 0.1)
				(type default)
			)
			(layer "B.Fab")
		)
		(fp_line
			(start -0.299974 -0.150114)
			(end -0.299974 0.150114)
			(stroke
				(width 0.1)
				(type default)
			)
			(layer "B.Fab")
		)
		(fp_line
			(start 0.299974 -0.150114)
			(end -0.299974 -0.150114)
			(stroke
				(width 0.1)
				(type default)
			)
			(layer "B.Fab")
		)
		(pad "1" smd rect
			(at 0.2667 0 90)
			(size 0.3048 0.381)
			(layers "B.Cu" "B.Mask" "B.Paste")
			(net "P0V9_CPU0_RT1_2A")
		)
		(pad "2" smd rect
			(at -0.2667 0 90)
			(size 0.3048 0.381)
			(layers "B.Cu" "B.Mask" "B.Paste")
			(net "GND")
		)
	)
	(footprint ""
		(layer "B.Cu")
		(at 99.103434 -252.599952 180)
		(property "Reference" "C2663"
			(at 0 0 0)
			(layer "B.SilkS")
			(hide yes)
			(effects
				(font
					(size 1.27 1.27)
				)
				(justify mirror)
			)
		)
		(property "Value" ""
			(at 0 0 0)
			(layer "B.Fab")
			(effects
				(font
					(size 1.27 1.27)
				)
				(justify mirror)
			)
		)
		(duplicate_pad_numbers_are_jumpers no)
		(fp_line
			(start 0.7874 0.4064)
			(end 0.7874 -0.4064)
			(stroke
				(width 0.1524)
				(type default)
			)
			(layer "B.SilkS")
		)
		(fp_line
			(start 0.7874 -0.4064)
			(end -0.7874 -0.4064)
			(stroke
				(width 0.1524)
				(type default)
			)
			(layer "B.SilkS")
		)
		(fp_line
			(start -0.7874 0.4064)
			(end 0.7874 0.4064)
			(stroke
				(width 0.1524)
				(type default)
			)
			(layer "B.SilkS")
		)
		(fp_line
			(start -0.7874 -0.4064)
			(end -0.7874 0.4064)
			(stroke
				(width 0.1524)
				(type default)
			)
			(layer "B.SilkS")
		)
		(fp_line
			(start 0.67945 0.3048)
			(end 0.67945 -0.305054)
			(stroke
				(width 0.1)
				(type default)
			)
			(layer "B.Fab")
		)
		(fp_line
			(start 0.67945 -0.305054)
			(end 0.12065 -0.305054)
			(stroke
				(width 0.1)
				(type default)
			)
			(layer "B.Fab")
		)
		(fp_line
			(start 0.12065 0.3048)
			(end 0.67945 0.3048)
			(stroke
				(width 0.1)
				(type default)
			)
			(layer "B.Fab")
		)
		(fp_line
			(start 0.12065 0.2794)
			(end 0.12065 0.3048)
			(stroke
				(width 0.1)
				(type default)
			)
			(layer "B.Fab")
		)
		(fp_line
			(start 0.12065 -0.2794)
			(end -0.12065 -0.2794)
			(stroke
				(width 0.1)
				(type default)
			)
			(layer "B.Fab")
		)
		(fp_line
			(start 0.12065 -0.305054)
			(end 0.12065 -0.2794)
			(stroke
				(width 0.1)
				(type default)
			)
			(layer "B.Fab")
		)
		(fp_line
			(start -0.120396 0.3048)
			(end -0.120396 0.2794)
			(stroke
				(width 0.1)
				(type default)
			)
			(layer "B.Fab")
		)
		(fp_line
			(start -0.120396 0.2794)
			(end 0.12065 0.2794)
			(stroke
				(width 0.1)
				(type default)
			)
			(layer "B.Fab")
		)
		(fp_line
			(start -0.12065 -0.2794)
			(end -0.12065 -0.3048)
			(stroke
				(width 0.1)
				(type default)
			)
			(layer "B.Fab")
		)
		(fp_line
			(start -0.12065 -0.3048)
			(end -0.67945 -0.3048)
			(stroke
				(width 0.1)
				(type default)
			)
			(layer "B.Fab")
		)
		(fp_line
			(start -0.67945 0.3048)
			(end -0.120396 0.3048)
			(stroke
				(width 0.1)
				(type default)
			)
			(layer "B.Fab")
		)
		(fp_line
			(start -0.67945 -0.3048)
			(end -0.67945 0.3048)
			(stroke
				(width 0.1)
				(type default)
			)
			(layer "B.Fab")
		)
		(pad "1" smd circle
			(at 0.40005 0)
			(size 0 0)
			(layers "B.Cu" "B.Mask" "B.Paste")
			(net "PVDD18_S5_P1")
		)
		(pad "2" smd circle
			(at -0.40005 0)
			(size 0 0)
			(layers "B.Cu" "B.Mask" "B.Paste")
			(net "GND")
		)
	)
)
